(kicad_pcb
	(version 20260206)
	(generator "pcbnew")
	(generator_version "10.0")
	(general
		(thickness 1.6)
		(legacy_teardrops no)
	)
	(paper "A4")
	(title_block
		(title "01162023_DA0F0TEBIF0_F0T_Expander_BD_F_brd_V02_OCP.brd")
		(comment 1 "Grand Teton / footprints 713-717 of 9728")
	)
	(layers
		(0 "F.Cu" signal "TOP")
		(4 "In1.Cu" signal "GND")
		(6 "In2.Cu" signal "VCC")
		(8 "In3.Cu" signal "VCC1")
		(10 "In4.Cu" signal "GND1")
		(12 "In5.Cu" signal "IN1")
		(14 "In6.Cu" signal "GND2")
		(16 "In7.Cu" signal "IN2")
		(18 "In8.Cu" signal "GND3")
		(20 "In9.Cu" signal "IN3")
		(22 "In10.Cu" signal "GND4")
		(24 "In11.Cu" signal "IN4")
		(26 "In12.Cu" signal "GND5")
		(28 "In13.Cu" signal "IN5")
		(30 "In14.Cu" signal "GND6")
		(32 "In15.Cu" signal "IN6")
		(34 "In16.Cu" signal "GND7")
		(2 "B.Cu" signal "BOTTOM")
		(9 "F.Adhes" user "F.Adhesive")
		(11 "B.Adhes" user "B.Adhesive")
		(13 "F.Paste" user "Package Geometry/Pastemask Top")
		(15 "B.Paste" user "Package Geometry/Pastemask Bottom")
		(5 "F.SilkS" user "Ref Des/Silkscreen Top")
		(7 "B.SilkS" user "Ref Des/Silkscreen Bottom")
		(1 "F.Mask" user "Board Geometry/Soldermask Top")
		(3 "B.Mask" user "Board Geometry/Soldermask Bottom")
		(17 "Dwgs.User" user "User.Drawings")
		(19 "Cmts.User" user "User.Comments")
		(21 "Eco1.User" user "User.Eco1")
		(23 "Eco2.User" user "User.Eco2")
		(25 "Edge.Cuts" user "Board Geometry/Outline")
		(27 "Margin" user)
		(31 "F.CrtYd" user "Package Geometry/Place Bound Top")
		(29 "B.CrtYd" user "Package Geometry/Place Bound Bottom")
		(35 "F.Fab" user "Ref Des/Assembly Top")
		(33 "B.Fab" user "Ref Des/Assembly Bottom")
	)
	(footprint ""
		(layer "F.Cu")
		(at 151.53259 -381.370332 180)
		(property "Reference" "C4100"
			(at 0 0 180)
			(layer "F.SilkS")
			(hide yes)
			(effects
				(font
					(size 1.27 1.27)
				)
			)
		)
		(property "Value" ""
			(at 0 0 180)
			(layer "F.Fab")
			(effects
				(font
					(size 1.27 1.27)
				)
			)
		)
		(duplicate_pad_numbers_are_jumpers no)
		(fp_line
			(start 0.7874 0.4064)
			(end -0.7874 0.4064)
			(stroke
				(width 0.1524)
				(type default)
			)
			(layer "F.SilkS")
		)
		(fp_line
			(start 0.7874 -0.4064)
			(end 0.7874 0.4064)
			(stroke
				(width 0.1524)
				(type default)
			)
			(layer "F.SilkS")
		)
		(fp_line
			(start -0.7874 0.4064)
			(end -0.7874 -0.4064)
			(stroke
				(width 0.1524)
				(type default)
			)
			(layer "F.SilkS")
		)
		(fp_line
			(start -0.7874 -0.4064)
			(end 0.7874 -0.4064)
			(stroke
				(width 0.1524)
				(type default)
			)
			(layer "F.SilkS")
		)
		(fp_line
			(start 0.67945 0.3048)
			(end 0.120396 0.3048)
			(stroke
				(width 0.1)
				(type default)
			)
			(layer "F.Fab")
		)
		(fp_line
			(start 0.67945 -0.3048)
			(end 0.67945 0.3048)
			(stroke
				(width 0.1)
				(type default)
			)
			(layer "F.Fab")
		)
		(fp_line
			(start 0.12065 -0.2794)
			(end 0.12065 -0.3048)
			(stroke
				(width 0.1)
				(type default)
			)
			(layer "F.Fab")
		)
		(fp_line
			(start 0.12065 -0.3048)
			(end 0.67945 -0.3048)
			(stroke
				(width 0.1)
				(type default)
			)
			(layer "F.Fab")
		)
		(fp_line
			(start 0.120396 0.3048)
			(end 0.120396 0.2794)
			(stroke
				(width 0.1)
				(type default)
			)
			(layer "F.Fab")
		)
		(fp_line
			(start 0.120396 0.2794)
			(end -0.12065 0.2794)
			(stroke
				(width 0.1)
				(type default)
			)
			(layer "F.Fab")
		)
		(fp_line
			(start -0.12065 0.3048)
			(end -0.67945 0.3048)
			(stroke
				(width 0.1)
				(type default)
			)
			(layer "F.Fab")
		)
		(fp_line
			(start -0.12065 0.2794)
			(end -0.12065 0.3048)
			(stroke
				(width 0.1)
				(type default)
			)
			(layer "F.Fab")
		)
		(fp_line
			(start -0.12065 -0.2794)
			(end 0.12065 -0.2794)
			(stroke
				(width 0.1)
				(type default)
			)
			(layer "F.Fab")
		)
		(fp_line
			(start -0.12065 -0.305054)
			(end -0.12065 -0.2794)
			(stroke
				(width 0.1)
				(type default)
			)
			(layer "F.Fab")
		)
		(fp_line
			(start -0.67945 0.3048)
			(end -0.67945 -0.305054)
			(stroke
				(width 0.1)
				(type default)
			)
			(layer "F.Fab")
		)
		(fp_line
			(start -0.67945 -0.305054)
			(end -0.12065 -0.305054)
			(stroke
				(width 0.1)
				(type default)
			)
			(layer "F.Fab")
		)
		(pad "1" smd circle
			(at -0.40005 0 180)
			(size 0 0)
			(layers "F.Cu" "F.Mask" "F.Paste")
			(net "GND")
		)
		(pad "2" smd circle
			(at 0.40005 0 180)
			(size 0 0)
			(layers "F.Cu" "F.Mask" "F.Paste")
			(net "GPU_3V3IO_RSVD1_FFU")
		)
	)
	(footprint ""
		(layer "F.Cu")
		(at 104.31526 -279.101804)
		(property "Reference" "PC58"
			(at 0 0 0)
			(layer "F.SilkS")
			(hide yes)
			(effects
				(font
					(size 1.27 1.27)
				)
			)
		)
		(property "Value" ""
			(at 0 0 0)
			(layer "F.Fab")
			(effects
				(font
					(size 1.27 1.27)
				)
			)
		)
		(duplicate_pad_numbers_are_jumpers no)
		(fp_line
			(start -0.7874 -0.4064)
			(end 0.7874 -0.4064)
			(stroke
				(width 0.1524)
				(type default)
			)
			(layer "F.SilkS")
		)
		(fp_line
			(start -0.7874 0.4064)
			(end -0.7874 -0.4064)
			(stroke
				(width 0.1524)
				(type default)
			)
			(layer "F.SilkS")
		)
		(fp_line
			(start 0.7874 -0.4064)
			(end 0.7874 0.4064)
			(stroke
				(width 0.1524)
				(type default)
			)
			(layer "F.SilkS")
		)
		(fp_line
			(start 0.7874 0.4064)
			(end -0.7874 0.4064)
			(stroke
				(width 0.1524)
				(type default)
			)
			(layer "F.SilkS")
		)
		(fp_line
			(start -0.67945 -0.305054)
			(end -0.12065 -0.305054)
			(stroke
				(width 0.1)
				(type default)
			)
			(layer "F.Fab")
		)
		(fp_line
			(start -0.67945 0.3048)
			(end -0.67945 -0.305054)
			(stroke
				(width 0.1)
				(type default)
			)
			(layer "F.Fab")
		)
		(fp_line
			(start -0.12065 -0.305054)
			(end -0.12065 -0.2794)
			(stroke
				(width 0.1)
				(type default)
			)
			(layer "F.Fab")
		)
		(fp_line
			(start -0.12065 -0.2794)
			(end 0.12065 -0.2794)
			(stroke
				(width 0.1)
				(type default)
			)
			(layer "F.Fab")
		)
		(fp_line
			(start -0.12065 0.2794)
			(end -0.12065 0.3048)
			(stroke
				(width 0.1)
				(type default)
			)
			(layer "F.Fab")
		)
		(fp_line
			(start -0.12065 0.3048)
			(end -0.67945 0.3048)
			(stroke
				(width 0.1)
				(type default)
			)
			(layer "F.Fab")
		)
		(fp_line
			(start 0.120396 0.2794)
			(end -0.12065 0.2794)
			(stroke
				(width 0.1)
				(type default)
			)
			(layer "F.Fab")
		)
		(fp_line
			(start 0.120396 0.3048)
			(end 0.120396 0.2794)
			(stroke
				(width 0.1)
				(type default)
			)
			(layer "F.Fab")
		)
		(fp_line
			(start 0.12065 -0.3048)
			(end 0.67945 -0.3048)
			(stroke
				(width 0.1)
				(type default)
			)
			(layer "F.Fab")
		)
		(fp_line
			(start 0.12065 -0.2794)
			(end 0.12065 -0.3048)
			(stroke
				(width 0.1)
				(type default)
			)
			(layer "F.Fab")
		)
		(fp_line
			(start 0.67945 -0.3048)
			(end 0.67945 0.3048)
			(stroke
				(width 0.1)
				(type default)
			)
			(layer "F.Fab")
		)
		(fp_line
			(start 0.67945 0.3048)
			(end 0.120396 0.3048)
			(stroke
				(width 0.1)
				(type default)
			)
			(layer "F.Fab")
		)
		(pad "1" smd circle
			(at -0.40005 0)
			(size 0 0)
			(layers "F.Cu" "F.Mask" "F.Paste")
			(net "SW_P12V_P0V8_PEX0_FLT")
		)
		(pad "2" smd circle
			(at 0.40005 0)
			(size 0 0)
			(layers "F.Cu" "F.Mask" "F.Paste")
			(net "GND")
		)
	)
	(footprint ""
		(layer "F.Cu")
		(at 54.341776 -27.006296 -90)
		(property "Reference" "PR6924"
			(at 0 0 270)
			(layer "F.SilkS")
			(hide yes)
			(effects
				(font
					(size 1.27 1.27)
				)
			)
		)
		(property "Value" ""
			(at 0 0 270)
			(layer "F.Fab")
			(effects
				(font
					(size 1.27 1.27)
				)
			)
		)
		(duplicate_pad_numbers_are_jumpers no)
		(fp_line
			(start -0.7874 0.4064)
			(end -0.7874 -0.4064)
			(stroke
				(width 0.1524)
				(type default)
			)
			(layer "F.SilkS")
		)
		(fp_line
			(start 0.7874 0.4064)
			(end -0.7874 0.4064)
			(stroke
				(width 0.1524)
				(type default)
			)
			(layer "F.SilkS")
		)
		(fp_line
			(start -0.7874 -0.4064)
			(end 0.7874 -0.4064)
			(stroke
				(width 0.1524)
				(type default)
			)
			(layer "F.SilkS")
		)
		(fp_line
			(start 0.7874 -0.4064)
			(end 0.7874 0.4064)
			(stroke
				(width 0.1524)
				(type default)
			)
			(layer "F.SilkS")
		)
		(fp_line
			(start -0.67945 0.3048)
			(end -0.67945 -0.305054)
			(stroke
				(width 0.1)
				(type default)
			)
			(layer "F.Fab")
		)
		(fp_line
			(start -0.12065 0.3048)
			(end -0.67945 0.3048)
			(stroke
				(width 0.1)
				(type default)
			)
			(layer "F.Fab")
		)
		(fp_line
			(start 0.120396 0.3048)
			(end 0.120396 0.2794)
			(stroke
				(width 0.1)
				(type default)
			)
			(layer "F.Fab")
		)
		(fp_line
			(start 0.67945 0.3048)
			(end 0.120396 0.3048)
			(stroke
				(width 0.1)
				(type default)
			)
			(layer "F.Fab")
		)
		(fp_line
			(start -0.12065 0.2794)
			(end -0.12065 0.3048)
			(stroke
				(width 0.1)
				(type default)
			)
			(layer "F.Fab")
		)
		(fp_line
			(start 0.120396 0.2794)
			(end -0.12065 0.2794)
			(stroke
				(width 0.1)
				(type default)
			)
			(layer "F.Fab")
		)
		(fp_line
			(start -0.12065 -0.2794)
			(end 0.12065 -0.2794)
			(stroke
				(width 0.1)
				(type default)
			)
			(layer "F.Fab")
		)
		(fp_line
			(start 0.12065 -0.2794)
			(end 0.12065 -0.3048)
			(stroke
				(width 0.1)
				(type default)
			)
			(layer "F.Fab")
		)
		(fp_line
			(start 0.12065 -0.3048)
			(end 0.67945 -0.3048)
			(stroke
				(width 0.1)
				(type default)
			)
			(layer "F.Fab")
		)
		(fp_line
			(start 0.67945 -0.3048)
			(end 0.67945 0.3048)
			(stroke
				(width 0.1)
				(type default)
			)
			(layer "F.Fab")
		)
		(fp_line
			(start -0.67945 -0.305054)
			(end -0.12065 -0.305054)
			(stroke
				(width 0.1)
				(type default)
			)
			(layer "F.Fab")
		)
		(fp_line
			(start -0.12065 -0.305054)
			(end -0.12065 -0.2794)
			(stroke
				(width 0.1)
				(type default)
			)
			(layer "F.Fab")
		)
		(pad "1" smd circle
			(at -0.40005 0 270)
			(size 0 0)
			(layers "F.Cu" "F.Mask" "F.Paste")
			(net "P3V3_SSD2_CO_ILIMIT")
		)
		(pad "2" smd circle
			(at 0.40005 0 270)
			(size 0 0)
			(layers "F.Cu" "F.Mask" "F.Paste")
			(net "GND")
		)
	)
	(footprint ""
		(layer "F.Cu")
		(at 263.497314 -346.712286)
		(property "Reference" "R6801"
			(at 0 0 0)
			(layer "F.SilkS")
			(hide yes)
			(effects
				(font
					(size 1.27 1.27)
				)
			)
		)
		(property "Value" ""
			(at 0 0 0)
			(layer "F.Fab")
			(effects
				(font
					(size 1.27 1.27)
				)
			)
		)
		(duplicate_pad_numbers_are_jumpers no)
		(fp_line
			(start -0.7874 -0.4064)
			(end 0.7874 -0.4064)
			(stroke
				(width 0.1524)
				(type default)
			)
			(layer "F.SilkS")
		)
		(fp_line
			(start -0.7874 0.4064)
			(end -0.7874 -0.4064)
			(stroke
				(width 0.1524)
				(type default)
			)
			(layer "F.SilkS")
		)
		(fp_line
			(start 0.7874 -0.4064)
			(end 0.7874 0.4064)
			(stroke
				(width 0.1524)
				(type default)
			)
			(layer "F.SilkS")
		)
		(fp_line
			(start 0.7874 0.4064)
			(end -0.7874 0.4064)
			(stroke
				(width 0.1524)
				(type default)
			)
			(layer "F.SilkS")
		)
		(fp_line
			(start -0.67945 -0.305054)
			(end -0.12065 -0.305054)
			(stroke
				(width 0.1)
				(type default)
			)
			(layer "F.Fab")
		)
		(fp_line
			(start -0.67945 0.3048)
			(end -0.67945 -0.305054)
			(stroke
				(width 0.1)
				(type default)
			)
			(layer "F.Fab")
		)
		(fp_line
			(start -0.12065 -0.305054)
			(end -0.12065 -0.2794)
			(stroke
				(width 0.1)
				(type default)
			)
			(layer "F.Fab")
		)
		(fp_line
			(start -0.12065 -0.2794)
			(end 0.12065 -0.2794)
			(stroke
				(width 0.1)
				(type default)
			)
			(layer "F.Fab")
		)
		(fp_line
			(start -0.12065 0.2794)
			(end -0.12065 0.3048)
			(stroke
				(width 0.1)
				(type default)
			)
			(layer "F.Fab")
		)
		(fp_line
			(start -0.12065 0.3048)
			(end -0.67945 0.3048)
			(stroke
				(width 0.1)
				(type default)
			)
			(layer "F.Fab")
		)
		(fp_line
			(start 0.120396 0.2794)
			(end -0.12065 0.2794)
			(stroke
				(width 0.1)
				(type default)
			)
			(layer "F.Fab")
		)
		(fp_line
			(start 0.120396 0.3048)
			(end 0.120396 0.2794)
			(stroke
				(width 0.1)
				(type default)
			)
			(layer "F.Fab")
		)
		(fp_line
			(start 0.12065 -0.3048)
			(end 0.67945 -0.3048)
			(stroke
				(width 0.1)
				(type default)
			)
			(layer "F.Fab")
		)
		(fp_line
			(start 0.12065 -0.2794)
			(end 0.12065 -0.3048)
			(stroke
				(width 0.1)
				(type default)
			)
			(layer "F.Fab")
		)
		(fp_line
			(start 0.67945 -0.3048)
			(end 0.67945 0.3048)
			(stroke
				(width 0.1)
				(type default)
			)
			(layer "F.Fab")
		)
		(fp_line
			(start 0.67945 0.3048)
			(end 0.120396 0.3048)
			(stroke
				(width 0.1)
				(type default)
			)
			(layer "F.Fab")
		)
		(pad "1" smd circle
			(at -0.40005 0)
			(size 0 0)
			(layers "F.Cu" "F.Mask" "F.Paste")
			(net "HSC_CSOUT")
		)
		(pad "2" smd circle
			(at 0.40005 0)
			(size 0 0)
			(layers "F.Cu" "F.Mask" "F.Paste")
			(net "HSC_D_OC_R")
		)
	)
	(footprint ""
		(layer "F.Cu")
		(at 374.325134 -14.735302 180)
		(property "Reference" "C2736"
			(at 0 0 180)
			(layer "F.SilkS")
			(hide yes)
			(effects
				(font
					(size 1.27 1.27)
				)
			)
		)
		(property "Value" ""
			(at 0 0 180)
			(layer "F.Fab")
			(effects
				(font
					(size 1.27 1.27)
				)
			)
		)
		(duplicate_pad_numbers_are_jumpers no)
		(fp_line
			(start 0.7874 0.4064)
			(end -0.7874 0.4064)
			(stroke
				(width 0.1524)
				(type default)
			)
			(layer "F.SilkS")
		)
		(fp_line
			(start 0.7874 -0.4064)
			(end 0.7874 0.4064)
			(stroke
				(width 0.1524)
				(type default)
			)
			(layer "F.SilkS")
		)
		(fp_line
			(start -0.7874 0.4064)
			(end -0.7874 -0.4064)
			(stroke
				(width 0.1524)
				(type default)
			)
			(layer "F.SilkS")
		)
		(fp_line
			(start -0.7874 -0.4064)
			(end 0.7874 -0.4064)
			(stroke
				(width 0.1524)
				(type default)
			)
			(layer "F.SilkS")
		)
		(fp_line
			(start 0.67945 0.3048)
			(end 0.120396 0.3048)
			(stroke
				(width 0.1)
				(type default)
			)
			(layer "F.Fab")
		)
		(fp_line
			(start 0.67945 -0.3048)
			(end 0.67945 0.3048)
			(stroke
				(width 0.1)
				(type default)
			)
			(layer "F.Fab")
		)
		(fp_line
			(start 0.12065 -0.2794)
			(end 0.12065 -0.3048)
			(stroke
				(width 0.1)
				(type default)
			)
			(layer "F.Fab")
		)
		(fp_line
			(start 0.12065 -0.3048)
			(end 0.67945 -0.3048)
			(stroke
				(width 0.1)
				(type default)
			)
			(layer "F.Fab")
		)
		(fp_line
			(start 0.120396 0.3048)
			(end 0.120396 0.2794)
			(stroke
				(width 0.1)
				(type default)
			)
			(layer "F.Fab")
		)
		(fp_line
			(start 0.120396 0.2794)
			(end -0.12065 0.2794)
			(stroke
				(width 0.1)
				(type default)
			)
			(layer "F.Fab")
		)
		(fp_line
			(start -0.12065 0.3048)
			(end -0.67945 0.3048)
			(stroke
				(width 0.1)
				(type default)
			)
			(layer "F.Fab")
		)
		(fp_line
			(start -0.12065 0.2794)
			(end -0.12065 0.3048)
			(stroke
				(width 0.1)
				(type default)
			)
			(layer "F.Fab")
		)
		(fp_line
			(start -0.12065 -0.2794)
			(end 0.12065 -0.2794)
			(stroke
				(width 0.1)
				(type default)
			)
			(layer "F.Fab")
		)
		(fp_line
			(start -0.12065 -0.305054)
			(end -0.12065 -0.2794)
			(stroke
				(width 0.1)
				(type default)
			)
			(layer "F.Fab")
		)
		(fp_line
			(start -0.67945 0.3048)
			(end -0.67945 -0.305054)
			(stroke
				(width 0.1)
				(type default)
			)
			(layer "F.Fab")
		)
		(fp_line
			(start -0.67945 -0.305054)
			(end -0.12065 -0.305054)
			(stroke
				(width 0.1)
				(type default)
			)
			(layer "F.Fab")
		)
		(pad "1" smd circle
			(at -0.40005 0 180)
			(size 0 0)
			(layers "F.Cu" "F.Mask" "F.Paste")
			(net "GND")
		)
		(pad "2" smd circle
			(at 0.40005 0 180)
			(size 0 0)
			(layers "F.Cu" "F.Mask" "F.Paste")
			(net "P3V3_SSD12")
		)
	)
)
